# Stackup_F0T_FIO_4L_1p6mm_IT-170GT_RTF_Rev0p1_20211105.xls — Manufacuring violation (pcb-stackup)
| Description | Quanta layout design rule | The stackup design rule |  |
| Min. Innerlayer Line Width, 0.5 oz copper (mil) | 3 | NA | Normal |
| Min. Innerlayer Space, 0.5 oz copper (mil) | 3.5 | NA | Medium |
| Min. Innerlayer Line Width,   1 oz copper (mil) | 4 | NA | High |
| Min. Innerlayer Space, 1 oz copper (mil) | 4 | NA |  |
| Min. Innerlayer Line Width,   2oz copper (mil) | 6 | NA |  |
| Min. Innerlayer Space,  2oz copper (mil) | 6 | NA |  |
| Min. Outerlayer line width, 0.5oz copper foil (mil) | 3.5 | 3.9 |  |
| Min. Outerlayer Space, 0.5oz copper foil (mil) | 3.5 | 4 |  |
| Min. Inner Core/PP thickness (mil) | 3 | 47.3 |  |
| Max. Aspect Ratio for min. DHS | 12.24 | 6.43 |  |
